# SCM (Grand Teton) — schematic parts with pin connectivity, parts 843–1005 of 1428; source: Cadence DE-HDL packaged netlist (pstxprt.dat, pstxnet.dat, pstchip.dat)

R337  Q_RES  120 1% CHIP  pkg 0402LF  page 20 : 1 = GND ; 2 = M_BMC_DDR4_MA<11>
R338  Q_RES  120 1% CHIP  pkg 0402LF  page 20 : 1 = GND ; 2 = M_BMC_DDR4_MA<12>
R339  Q_RES  120 1% CHIP  pkg 0402LF  page 20 : 1 = GND ; 2 = M_BMC_DDR4_MA<13>
R340  Q_RES  120 1% CHIP  pkg 0402LF  page 20 : 1 = GND ; 2 = M_BMC_DDR4_MWE_N
R341  Q_RES  120 1% CHIP  pkg 0402LF  page 20 : 1 = GND ; 2 = M_BMC_DDR4_MCAS_N
R342  Q_RES  120 1% CHIP  pkg 0402LF  page 20 : 1 = GND ; 2 = M_BMC_DDR4_MRAS_N
R343  Q_RES  120 1% CHIP  pkg 0402LF  page 20 : 1 = GND ; 2 = M_BMC_DDR4_MCS_N
R344  Q_RES  120 1% CHIP  pkg 0402LF  page 20 : 1 = GND ; 2 = M_BMC_DDR4_MACT_N
R345  Q_RES  120 1% CHIP  pkg 0402LF  page 20 : 1 = GND ; 2 = M_BMC_DDR4_MBG0
R346  Q_RES  120 1% CHIP  pkg 0402LF  page 20 : 1 = GND ; 2 = M_BMC_DDR4_MBA0
R347  Q_RES  120 1% CHIP  pkg 0402LF  page 20 : 1 = GND ; 2 = M_BMC_DDR4_MBA1
R348  Q_RES  120 1% CHIP  pkg 0402LF  page 20 : 1 = GND ; 2 = M_BMC_DDR4_MODT
R349  Q_RES  120 1% CHIP  pkg 0402LF  page 20 : 1 = GND ; 2 = M_BMC_DDR4_MCKE
R350  Q_RES  120 1% EMPTY  pkg 0402LF  page 20 : 1 = GND ; 2 = M_BMC_DDR4_MBG1
R351  Q_RES  120 1% CHIP  pkg 0402LF  page 20 : 1 = M_BMC_DDR4_MA<0> ; 2 = P1V2_AUX
R352  Q_RES  120 1% CHIP  pkg 0402LF  page 20 : 1 = M_BMC_DDR4_MA<1> ; 2 = P1V2_AUX
R353  Q_RES  120 1% CHIP  pkg 0402LF  page 20 : 1 = M_BMC_DDR4_MA<2> ; 2 = P1V2_AUX
R354  Q_RES  120 1% CHIP  pkg 0402LF  page 20 : 1 = M_BMC_DDR4_MA<3> ; 2 = P1V2_AUX
R355  Q_RES  120 1% CHIP  pkg 0402LF  page 20 : 1 = M_BMC_DDR4_MA<4> ; 2 = P1V2_AUX
R356  Q_RES  120 1% CHIP  pkg 0402LF  page 20 : 1 = M_BMC_DDR4_MA<5> ; 2 = P1V2_AUX
R357  Q_RES  120 1% CHIP  pkg 0402LF  page 20 : 1 = M_BMC_DDR4_MA<6> ; 2 = P1V2_AUX
R358  Q_RES  120 1% CHIP  pkg 0402LF  page 20 : 1 = M_BMC_DDR4_MA<7> ; 2 = P1V2_AUX
R359  Q_RES  120 1% CHIP  pkg 0402LF  page 20 : 1 = M_BMC_DDR4_MA<8> ; 2 = P1V2_AUX
R360  Q_RES  120 1% CHIP  pkg 0402LF  page 20 : 1 = M_BMC_DDR4_MA<9> ; 2 = P1V2_AUX
R361  Q_RES  120 1% CHIP  pkg 0402LF  page 20 : 1 = M_BMC_DDR4_MA<10> ; 2 = P1V2_AUX
R362  Q_RES  120 1% CHIP  pkg 0402LF  page 20 : 1 = M_BMC_DDR4_MA<11> ; 2 = P1V2_AUX
R363  Q_RES  120 1% CHIP  pkg 0402LF  page 20 : 1 = M_BMC_DDR4_MA<12> ; 2 = P1V2_AUX
R364  Q_RES  120 1% CHIP  pkg 0402LF  page 20 : 1 = M_BMC_DDR4_MA<13> ; 2 = P1V2_AUX
R365  Q_RES  120 1% CHIP  pkg 0402LF  page 20 : 1 = M_BMC_DDR4_MWE_N ; 2 = P1V2_AUX
R366  Q_RES  120 1% CHIP  pkg 0402LF  page 20 : 1 = M_BMC_DDR4_MCAS_N ; 2 = P1V2_AUX
R367  Q_RES  120 1% CHIP  pkg 0402LF  page 20 : 1 = M_BMC_DDR4_MRAS_N ; 2 = P1V2_AUX
R368  Q_RES  120 1% CHIP  pkg 0402LF  page 20 : 1 = M_BMC_DDR4_MCS_N ; 2 = P1V2_AUX
R369  Q_RES  120 1% CHIP  pkg 0402LF  page 20 : 1 = M_BMC_DDR4_MACT_N ; 2 = P1V2_AUX
R370  Q_RES  120 1% CHIP  pkg 0402LF  page 20 : 1 = M_BMC_DDR4_MBG0 ; 2 = P1V2_AUX
R371  Q_RES  120 1% CHIP  pkg 0402LF  page 20 : 1 = M_BMC_DDR4_MBA0 ; 2 = P1V2_AUX
R372  Q_RES  120 1% CHIP  pkg 0402LF  page 20 : 1 = M_BMC_DDR4_MBA1 ; 2 = P1V2_AUX
R373  Q_RES  120 1% CHIP  pkg 0402LF  page 20 : 1 = M_BMC_DDR4_MODT ; 2 = P1V2_AUX
R374  Q_RES  120 1% CHIP  pkg 0402LF  page 20 : 1 = M_BMC_DDR4_MCKE ; 2 = P1V2_AUX
R375  Q_RES  120 1% EMPTY  pkg 0402LF  page 20 : 1 = M_BMC_DDR4_MBG1 ; 2 = P1V2_AUX
R376  Q_RES  4.7K 1% CHIP  pkg 0402LF  page 28 : 1 = P5V_AUX ; 2 = USB_OC0_EN
R377  Q_RES  10K 1% EMPTY  pkg 0402LF  page 28 : 1 = USB_OC0_EN ; 2 = GND
R378  Q_RES  20K 1% CHIP  pkg 0402LF  page 28 : 1 = USB_OC0_ILIM ; 2 = GND
R379  Q_RES  0 5% CHIP  pkg 0402LF  page 36 : 1 = PWRGD_P1V0_AUX_R1 ; 2 = PWRGD_P1V0_AUX
R380  Q_RES  100 1% CHIP  pkg 0402LF  page 52 : 1 = EN_P3V3_RGM ; 2 = EN_P3V3_RGM_R
R381  Q_RES  0 5% CHIP  pkg 0402LF  page 52 : 1 = EN_P3V3 ; 2 = PWRGD_EN_P3V3_R
R382  Q_RES  0 5% CHIP  pkg 0402LF  page 53 : 1 = PWRGD_P3V3_AUX ; 2 = PWRGD_P3V3_AUX_R2
R383  Q_RES  10K 1% CHIP  pkg 0402LF  page 28 : 1 = P3V3_AUX ; 2 = USB_OC0_REAR_N
R384  Q_RES  100 1% CHIP  pkg 0402LF  page 28 : 1 = USB_OC0_REAR_N ; 2 = USB_OC0_REAR_R_N
R385  Q_RES  0 5% CHIP  pkg 0402LF  page 29 : 1 = USB_FPNL_DN ; 2 = USB2_01_F_DN
R386  Q_RES  0 5% CHIP  pkg 0402LF  page 29 : 1 = USB_FPNL_DP ; 2 = USB2_01_F_DP
R387  Q_RES  100K 1% CHIP  pkg 0402LF  page 12 : 1 = GND ; 2 = DP_BMC_HPD_3V3_BUF
R388  Q_RES  33.2 1% CHIP  pkg 0402LF  page 22 : 1 = RST_SRST_PLD_BMC_R_N ; 2 = RST_SRST_PLD_BMC_R1_N
R389  Q_RES  316 1% CHIP  pkg 0402LF  page 50 : 1 = LED_D21_R1 ; 2 = P12V_AUX
R390  Q_RES  33.2 1% CHIP  pkg 0402LF  page 49 : 1 = FM_ID_LED ; 2 = FM_ID_R_LED
R391  Q_RES  8.2K 5% EMPTY  pkg 0402LF  page 50 : 1 = P3V3_AUX ; 2 = REAR_AC_PWR_BTN_N
R392  Q_RES  0 5% CHIP  pkg 0402LF  page 13 : 1 = RMII_OCP_RCLKI_ISO ; 2 = RMII_OCP_RCLKI_R_ISO
R393  Q_RES  0 5% CHIP  pkg 0402LF  page 54 : 1 = EN_P1V8 ; 2 = EN_P1V8_R
R394  Q_RES  33.2 1% CHIP  pkg 0402LF  page 12 : 1 = SMB_BMC_MM2_R_SDA ; 2 = SMB_BMC_MM2_SDA
R395  Q_RES  0 5% CHIP  pkg 0402LF  page 13 : 1 = PWRGD_P1V0_AUX_DELAY_R ; 2 = PWRGD_P1V0_AUX_DELAY
R396  Q_RES  100K 1% CHIP  pkg 0402LF  page 31 : 1 = P3V3_AUX ; 2 = UART_BIC_GF_RXD
R397  Q_RES  0 5% CHIP  pkg 0402LF  page 34 : 1 = JTAG_SCM_PLD_R_JTAGEN ; 2 = JTAG_SCM_PLD_JTAGEN
R398  Q_RES  0 5% CHIP  pkg 0402LF  page 15 : 1 = JTAG_1_BMC_TDO ; 2 = JTAG_1_BMC_TDO_R
R399  Q_RES  0 5% CHIP  pkg 0402LF  page 56 : 1 = EN_P1V0_AUX ; 2 = EN_P1V0_AUX_R
R400  Q_RES  4.7K 1% EMPTY  pkg 0402LF  page 12 : 1 = P3V3_AUX ; 2 = FM_THERMTRIP_DLY_LVC1_R_N
R401  Q_RES  33.2 1% CHIP  pkg 0402LF  page 13 : 1 = PU_BMC_FWSPIABR_N ; 2 = PU_BMC_FWSPIABR_N_R
R402  Q_RES  33.2 1% CHIP  pkg 0402LF  page 13 : 1 = PU_FWSPIWP_N ; 2 = PU_FWSPIWP_N_R
R403  Q_RES  10K 1% CHIP  pkg 0402LF  page 53 : 1 = P3V3_AUX ; 2 = PWRGD_P2V5_AUX_R
R404  Q_RES  10K 1% CHIP  pkg 0402LF  page 21 : 1 = P3V3_AUX ; 2 = BSM_PRSNT_N
R405  Q_RES  33.2 1% CHIP  pkg 0402LF  page 13 : 1 = PD_BIOS_MUX_EN_R_N ; 2 = PD_BIOS_MUX_EN_N
R406  Q_RES  10K 1% CHIP  pkg 0402LF  page 54 : 1 = P3V3_AUX ; 2 = PWRGD_P1V8_AUX_R
R407  Q_RES  33.2 1% CHIP  pkg 0402LF  page 13 : 1 = FM_BMC_SUSACK_R1_N ; 2 = FM_BMC_SUSACK_N
R408  Q_RES  4.7K 1% EMPTY  pkg 0402LF  page 46 : 1 = P3V3_AUX ; 2 = SPI_BMC_TPM_CLK
R409  Q_RES  49.9 1% CHIP  pkg 0402LF  page 26 : 1 = SMB_TMP421_BMC_MM2_SDA ; 2 = SMB_BMC_MM2_SDA
R410  Q_RES  49.9 1% CHIP  pkg 0402LF  page 26 : 1 = SMB_TMP421_BMC_MM2_SCL ; 2 = SMB_BMC_MM2_SCL
R411  Q_RES  100 1% CHIP  pkg 0402LF  page 26 : 1 = FRU_E0 ; 2 = GND
R412  Q_RES  100 1% CHIP  pkg 0402LF  page 26 : 1 = FRU_E1 ; 2 = GND
R413  Q_RES  100 1% CHIP  pkg 0402LF  page 26 : 1 = FRU_E2 ; 2 = GND
R414  Q_RES  4.7K 1% EMPTY  pkg 0402LF  page 46 : 1 = P3V3_AUX ; 2 = SPI_BMC_TPM_MISO
R415  Q_RES  2.2 1% CHIP  pkg 0402LF  page 52 : 1 = SW_P3V3_AUX_BST_R ; 2 = SW_P3V3_AUX_BST
R416  Q_RES  4.7K 1% CHIP  pkg 0402LF  page 26 : 1 = P3V3_AUX ; 2 = TMC75_A0
R417  Q_RES  1K 1% EMPTY  pkg 0402LF  page 26 : 1 = TMC75_A0 ; 2 = GND
R418  Q_RES  4.7K 1% EMPTY  pkg 0402LF  page 26 : 1 = P3V3_AUX ; 2 = TMC75_A2
R419  Q_RES  1K 1% CHIP  pkg 0402LF  page 26 : 1 = TMC75_A2 ; 2 = GND
R420  Q_RES  150 1% CHIP  pkg 0402LF  page 26 : 1 = SMB_BMC_MM16_R2_SCL ; 2 = SMB_BMC_MM16_SCL
R421  Q_RES  33.2 1% CHIP  pkg 0402LF  page 26 : 1 = SMB_BMC_MM16_R2_SDA ; 2 = SMB_BMC_MM16_SDA
R422  Q_RES  2.2K 5% CHIP  pkg 0402LF  page 27 : 1 = P3V3_AUX ; 2 = SMB_BMC_MM13_SCL
R423  Q_RES  33.2 1% CHIP  pkg 0402LF  page 12 : 1 = SMB_BMC_MM13_R_SCL ; 2 = SMB_BMC_MM13_SCL
R424  Q_RES  33.2 1% CHIP  pkg 0402LF  page 12 : 1 = SMB_BMC_MM13_R_SDA ; 2 = SMB_BMC_MM13_SDA
R425  Q_RES  33.2 1% CHIP  pkg 0402LF  page 12 : 1 = SMB_BMC_MM14_R_SCL ; 2 = SMB_BMC_MM14_SCL
R426  Q_RES  33.2 1% CHIP  pkg 0402LF  page 12 : 1 = SMB_BMC_MM14_R_SDA ; 2 = SMB_BMC_MM14_SDA
R427  Q_RES  33.2 1% CHIP  pkg 0402LF  page 13 : 1 = UART_BMC_1_RXD_R ; 2 = UART_BMC_1_RXD
R428  Q_RES  2.2K 5% CHIP  pkg 0402LF  page 27 : 1 = P3V3_AUX ; 2 = SMB_BMC_MM13_SDA
R429  Q_RES  2.2K 5% CHIP  pkg 0402LF  page 27 : 1 = P3V3_AUX ; 2 = SMB_BMC_MM14_SCL
R430  Q_RES  4.7K 1% CHIP  pkg 0402LF  page 27 : 1 = P3V3_AUX ; 2 = FM_BMC_ONCTL_R_N
R431  Q_RES  100 1% EMPTY  pkg 0402LF  page 48 : 1 = FM_BMC_DISABLE ; 2 = GND
R432  Q_RES  0 5% CHIP  pkg 0402LF  page 35 : 1 = FM_PWR_R_BTN ; 2 = FM_PWR_BTN
R433  Q_RES  33.2 1% CHIP  pkg 0402LF  page 12 : 1 = SGPIO_DI_1 ; 2 = SGPIO_BMC_M1_DI
R434  Q_RES  33.2 1% CHIP  pkg 0402LF  page 34 : 1 = SGPIO_CLK_PLD_0 ; 2 = SGPIO_CLK_0
R435  Q_RES  33.2 1% CHIP  pkg 0402LF  page 34 : 1 = SGPIO_PLD_DO_0 ; 2 = SGPIO_DO_0
R436  Q_RES  33.2 1% CHIP  pkg 0402LF  page 34 : 1 = SGPIO_PLD_LD_0 ; 2 = SGPIO_LD_0
R437  Q_RES  33.2 1% CHIP  pkg 0402LF  page 34 : 1 = SGPIO_PLD_DI_0 ; 2 = SGPIO_DI_0
R438  Q_RES  2.2K 5% CHIP  pkg 0402LF  page 27 : 1 = P3V3_AUX ; 2 = SMB_BMC_MM14_SDA
R439  Q_RES  33.2 1% CHIP  pkg 0402LF  page 13 : 1 = FM_PECI_SEL_N ; 2 = FM_PECI_SEL_R_N
R440  Q_RES  49.9 1% EMPTY  pkg 0402LF  page 15 : 1 = USB_HOST_BMC_A_DP ; 2 = GND
R441  Q_RES  49.9 1% EMPTY  pkg 0402LF  page 15 : 1 = USB_HOST_BMC_A_DN ; 2 = GND
R442  Q_RES  33.2 1% CHIP  pkg 0402LF  page 13 : 1 = SMB_BMC_ALERT3_N ; 2 = SMB_BMC_ALERT3_R_N
R443  Q_RES  33.2 1% CHIP  pkg 0402LF  page 13 : 1 = SMB_BMC_ALERT4_N ; 2 = SMB_BMC_ALERT4_R_N
R444  Q_RES  33.2 1% CHIP  pkg 0402LF  page 13 : 1 = FM_ESPI_PLD_EN ; 2 = FM_ESPI_PLD_R1_EN
R445  Q_RES  33.2 1% CHIP  pkg 0402LF  page 36 : 1 = FM_BMC_SUSACK_N ; 2 = FM_BMC_SUSACK_R2_N
R446  Q_RES  4.7K 1% CHIP  pkg 0402LF  page 13 : 1 = P3V3_AUX ; 2 = FM_PECI_SEL_N
R447  Q_RES  0 5% CHIP  pkg 0402LF  page 34 : 1 = RST_EXTRST_R_N ; 2 = RST_EXTRST_N
R448  Q_RES  33.2 1% CHIP  pkg 0402LF  page 15 : 1 = SMB_BMC_ALERT9_N ; 2 = SMB_BMC_ALERT9_R_N
R449  Q_RES  33.2 1% CHIP  pkg 0402LF  page 15 : 1 = SMB_BMC_ALERT10_N ; 2 = SMB_BMC_ALERT10_R_N
R450  Q_RES  0 5% CHIP  pkg 0402LF  page 22 : 1 = RST_BMC_SELF_HW ; 2 = RST_BMC_SELF_HW_R3
R451  Q_RES  0 5% CHIP  pkg 0402LF  page 22 : 1 = PWRGD_P1V0_AUX_DELAY ; 2 = PWRGD_P1V0_AUX_DELAY_R1
R452  Q_RES  4.7K 1% CHIP  pkg 0402LF  page 13 : 1 = P3V3_AUX ; 2 = RST_WDTRST_PLD_N
R453  Q_RES  0 5% CHIP  pkg 0402LF  page 35 : 1 = SMB_BMC_ALERT3_N ; 2 = SMB_BMC_ALERT3_R1_N
R454  Q_RES  0 5% CHIP  pkg 0402LF  page 35 : 1 = SMB_BMC_ALERT4_N ; 2 = SMB_BMC_ALERT4_R1_N
R455  Q_RES  33.2 1% CHIP  pkg 0402LF  page 10 : 1 = SMB_BMC_MM2_SCL ; 2 = SMB_BMC_MM2_SCL_R1
R456  Q_RES  0 5% CHIP  pkg 0402LF  page 35 : 1 = SMB_BMC_ALERT9_N ; 2 = SMB_BMC_ALERT9_R1_N
R457  Q_RES  0 5% CHIP  pkg 0402LF  page 35 : 1 = SMB_BMC_ALERT10_N ; 2 = SMB_BMC_ALERT10_R1_N
R458  Q_RES  33.2 1% CHIP  pkg 0402LF  page 13 : 1 = FM_DEBUG_PORT_PRSNT_R1_N ; 2 = FM_DEBUG_PORT_PRSNT_N
R459  Q_RES  33.2 1% CHIP  pkg 0402LF  page 34 : 1 = BSM_PRSNT_R_N ; 2 = BSM_PRSNT_R1_N
R460  Q_RES  33.2 1% CHIP  pkg 0402LF  page 13 : 1 = SPI_BMC_TPM_CS2_R_N ; 2 = SPI_BMC_TPM_CS2_R1_N
R461  Q_RES  33.2 1% CHIP  pkg 0402LF  page 13 : 1 = BMC_ID_BEEP_SEL ; 2 = BMC_ID_BEEP_SEL_R1
R462  Q_RES  4.7K 1% CHIP  pkg 0402LF  page 15 : 1 = P3V3_AUX ; 2 = SYS_BMC_PWRBTN_R1_N
R463  Q_RES  0 5% EMPTY  pkg 0402LF  page 35 : 1 = AC_PWR_BTN_R1_N ; 2 = AC_PWR_BTN_R2_N
R464  Q_RES  10K 1% CHIP  pkg 0402LF  page 46 : 1 = P3V3_AUX ; 2 = FM_TPM_PRSNT_0_N
R465  Q_RES  33.2 1% CHIP  pkg 0402LF  page 13 : 1 = FM_FLASH_LATCH_N_R1 ; 2 = FM_FLASH_LATCH_N
R466  Q_RES  33.2 1% CHIP  pkg 0402LF  page 13 : 1 = FLASH_WP_STATUS_R1 ; 2 = FLASH_WP_STATUS
R467  Q_RES  2K 1% CHIP  pkg 0402LF  page 44 : 1 = PD_BIOS_MUX_EN_N ; 2 = GND
R468  Q_RES  90.9 1% CHIP  pkg 0402LF  page 13 : 1 = SPI_BMC_TPM_CLK_R1 ; 2 = SPI_BMC_TPM_CLK
R469  Q_RES  33.2 1% CHIP  pkg 0402LF  page 13 : 1 = SPI_BMC_TPM_MISO_R1 ; 2 = SPI_BMC_TPM_MISO
R470  Q_RES  0 5% EMPTY  pkg 0402LF  page 50 : 1 = REAR_AC_PWR_BTN ; 2 = REAR_AC_PWR_BTN_N
R471  Q_RES  0 5% CHIP  pkg 0402LF  page 50 : 1 = REAR_AC_PWR_BTN ; 2 = AC_PWR_BTN_N
R472  Q_RES  4.7K 1% EMPTY  pkg 0402LF  page 35 : 1 = P3V3_AUX ; 2 = AC_PWR_BTN_R1_N
R479  Q_RES  33.2 1% CHIP  pkg 0402LF  page 15 : 1 = FM_P12V_HSC_ENABLE ; 2 = FM_P12V_HSC_ENABLE_R1
R481  Q_RES  33.2 1% CHIP  pkg 0402LF  page 45 : 1 = SPI_PCH_MUXED_CLK ; 2 = SPI_PCH_CLK_FLASH_R1
R482  Q_RES  33.2 1% CHIP  pkg 0402LF  page 45 : 1 = SPI_PCH_MUXED_IO0 ; 2 = SPI_PCH_IO0_FLASH_R1
R483  Q_RES  33.2 1% CHIP  pkg 0402LF  page 45 : 1 = SPI_PCH_MUXED_IO2 ; 2 = SPI_PCH_IO2_FLASH_R1
R484  Q_RES  33.2 1% CHIP  pkg 0402LF  page 45 : 1 = SPI_PCH_MUXED_IO1 ; 2 = SPI_PCH_IO1_FLASH_R1
R485  Q_RES  33.2 1% CHIP  pkg 0402LF  page 45 : 1 = SPI_PCH_MUXED_CS0_N ; 2 = SPI_PCH_CS0_FLASH_R1_N
R486  Q_RES  33.2 1% CHIP  pkg 0402LF  page 45 : 1 = SPI_PCH_MUXED_IO3 ; 2 = SPI_PCH_IO3_FLASH_R1
R487  Q_RES  4.7K 1% EMPTY  pkg 0402LF  page 45 : 1 = SPI_PCH_CS0_FLASH_R1_N ; 2 = GND
R488  Q_RES  4.7K 1% CHIP  pkg 0402LF  page 45 : 1 = P3V3_AUX ; 2 = SPI_PCH_IO2_FLASH_R1
R489  Q_RES  33.2 1% CHIP  pkg 0402LF  page 15 : 1 = FM_SOL_UART_CH_SEL ; 2 = FM_SOL_UART_CH_SEL_R1
R490  Q_RES  4.7K 1% CHIP  pkg 0402LF  page 45 : 1 = P3V3_AUX ; 2 = SPI_PCH_CS0_FLASH_R1_N
R491  Q_RES  4.7K 1% EMPTY  pkg 0402LF  page 15 : 1 = P3V3_RGM ; 2 = RST_BMC_SRST_N
R492  Q_RES  4.7K 1% CHIP  pkg 0402LF  page 45 : 1 = P3V3_AUX ; 2 = SPI_PCH_IO3_FLASH_R1
R493  Q_RES  150K 1% EMPTY  pkg 0402LF  page 17 : 1 = LPC_ESPI_SEL_N ; 2 = GND
R494  Q_RES  33.2 1% CHIP  pkg 0402LF  page 13 : 1 = RST_BMC_SELF_HW_R1 ; 2 = RST_BMC_SELF_HW
R496  Q_RES  4.7K 1% EMPTY  pkg 0402LF  page 45 : 1 = P3V3_AUX ; 2 = RST_SPI_PCH_FLASH_R1_N
R497  Q_RES  10K 1% CHIP  pkg 0402LF  page 46 : 1 = P3V3_AUX ; 2 = IRQ_PCH_TPM_SPI_N
R498  Q_RES  22 1% CHIP  pkg 0402LF  page 46 : 1 = SPI_SYS_R_MOSI ; 2 = SPI_SYS_R1_MOSI
R499  Q_RES  22 1% CHIP  pkg 0402LF  page 46 : 1 = SPI_SYS_R_MISO ; 2 = SPI_SYS_R1_MISO
R500  Q_RES  0 5% CHIP  pkg 0402LF  page 46 : 1 = SPI_TPM_CS_N_R ; 2 = SPI_TPM_CS_R_N
R501  Q_RES  33.2 1% CHIP  pkg 0402LF  page 46 : 1 = SPI_SYS_R1_CLK ; 2 = SPI_SYS_R_CLK
R503  Q_RES  0 5% CHIP  pkg 0402LF  page 46 : 1 = RST_PLTRST_TPM_N ; 2 = RST_PLTRST_N
R504  Q_RES  8.2K 5% CHIP  pkg 0402LF  page 50 : 1 = P3V3_AUX ; 2 = REAR_ID_RST_BTN_N
R505  Q_RES  0 5% CHIP  pkg 0402LF  page 46 : 1 = IRQ_PCH_TPM_SPI_N ; 2 = IRQ_PCH_TPM_SPI_R_N
R506  Q_RES  100 1% EMPTY  pkg 0402LF  page 48 : 1 = FM_BMC_DEBUG_SW_N ; 2 = GND
R507  Q_RES  100 1% EMPTY  pkg 0402LF  page 48 : 1 = MB_JTAG_PLD_R_JTAGEN ; 2 = GND
R508  Q_RES  10K 1% CHIP  pkg 0402LF  page 48 : 1 = P3V3_AUX ; 2 = MB_JTAG_PLD_R_JTAGEN
